# S9S_MB_2U (Grand Teton) — schematic netlist excerpt (pin names and nets, part order shuffled) for the footprints in the layout excerpt that follows; sources: Cadence DE-HDL packaged netlist, KiCad conversion of 03242023_DA0F0TMBIJ0_F0T_Motherboard_J_brd_V01_OCP.brd

R1856  Q_RES  100 1% CHIP  pkg 0402LF  page 242 : A = FM_SCM_PRSNT1_N ; B = FM_SCM_PRSNT1_R_N
R4303  Q_RES  22 1% CHIP  pkg 0402LF  page 179 : A = CLK_100M_E1S_0_R_DP ; B = CLK_100M_E1S_0_DP

(kicad_pcb
	(version 20260206)
	(generator "pcbnew")
	(generator_version "10.0")
	(general
		(thickness 1.6)
		(legacy_teardrops no)
	)
	(paper "A4")
	(title_block
		(title "03242023_DA0F0TMBIJ0_F0T_Motherboard_J_brd_V01_OCP.brd")
		(comment 1 "Grand Teton / footprints 1949-1950 of 6105")
	)
	(layers
		(0 "F.Cu" signal "TOP")
		(4 "In1.Cu" signal "GND")
		(6 "In2.Cu" signal "IN1")
		(8 "In3.Cu" signal "GND1")
		(10 "In4.Cu" signal "IN2")
		(12 "In5.Cu" signal "GND2")
		(14 "In6.Cu" signal "IN3")
		(16 "In7.Cu" signal "GND3")
		(18 "In8.Cu" signal "VCC")
		(20 "In9.Cu" signal "VCC1")
		(22 "In10.Cu" signal "GND4")
		(24 "In11.Cu" signal "IN4")
		(26 "In12.Cu" signal "GND5")
		(28 "In13.Cu" signal "IN5")
		(30 "In14.Cu" signal "GND6")
		(32 "In15.Cu" signal "IN6")
		(34 "In16.Cu" signal "GND7")
		(2 "B.Cu" signal "BOTTOM")
		(9 "F.Adhes" user "F.Adhesive")
		(11 "B.Adhes" user "B.Adhesive")
		(13 "F.Paste" user "Package Geometry/Pastemask Top")
		(15 "B.Paste" user "Package Geometry/Pastemask Bottom")
		(5 "F.SilkS" user "Ref Des/Silkscreen Top")
		(7 "B.SilkS" user "Ref Des/Silkscreen Bottom")
		(1 "F.Mask" user "Board Geometry/Soldermask Top")
		(3 "B.Mask" user "Board Geometry/Soldermask Bottom")
		(17 "Dwgs.User" user "User.Drawings")
		(19 "Cmts.User" user "User.Comments")
		(21 "Eco1.User" user "User.Eco1")
		(23 "Eco2.User" user "User.Eco2")
		(25 "Edge.Cuts" user "Board Geometry/Outline")
		(27 "Margin" user)
		(31 "F.CrtYd" user "Package Geometry/Place Bound Top")
		(29 "B.CrtYd" user "Package Geometry/Place Bound Bottom")
		(35 "F.Fab" user "Ref Des/Assembly Top")
		(33 "B.Fab" user "Ref Des/Assembly Bottom")
	)
	(footprint ""
		(layer "F.Cu")
		(at 189.79769 -36.0807)
		(property "Reference" "R1856"
			(at 0 0 0)
			(layer "F.SilkS")
			(hide yes)
			(effects
				(font
					(size 1.27 1.27)
				)
			)
		)
		(property "Value" ""
			(at 0 0 0)
			(layer "F.Fab")
			(effects
				(font
					(size 1.27 1.27)
				)
			)
		)
		(duplicate_pad_numbers_are_jumpers no)
		(fp_line
			(start -0.7874 -0.4064)
			(end 0.7874 -0.4064)
			(stroke
				(width 0.1524)
				(type default)
			)
			(layer "F.SilkS")
		)
		(fp_line
			(start -0.7874 0.4064)
			(end -0.7874 -0.4064)
			(stroke
				(width 0.1524)
				(type default)
			)
			(layer "F.SilkS")
		)
		(fp_line
			(start 0.7874 -0.4064)
			(end 0.7874 0.4064)
			(stroke
				(width 0.1524)
				(type default)
			)
			(layer "F.SilkS")
		)
		(fp_line
			(start 0.7874 0.4064)
			(end -0.7874 0.4064)
			(stroke
				(width 0.1524)
				(type default)
			)
			(layer "F.SilkS")
		)
		(fp_line
			(start -0.67945 -0.305054)
			(end -0.12065 -0.305054)
			(stroke
				(width 0.1)
				(type default)
			)
			(layer "F.Fab")
		)
		(fp_line
			(start -0.67945 0.3048)
			(end -0.67945 -0.305054)
			(stroke
				(width 0.1)
				(type default)
			)
			(layer "F.Fab")
		)
		(fp_line
			(start -0.12065 -0.305054)
			(end -0.12065 -0.2794)
			(stroke
				(width 0.1)
				(type default)
			)
			(layer "F.Fab")
		)
		(fp_line
			(start -0.12065 -0.2794)
			(end 0.12065 -0.2794)
			(stroke
				(width 0.1)
				(type default)
			)
			(layer "F.Fab")
		)
		(fp_line
			(start -0.12065 0.2794)
			(end -0.12065 0.3048)
			(stroke
				(width 0.1)
				(type default)
			)
			(layer "F.Fab")
		)
		(fp_line
			(start -0.12065 0.3048)
			(end -0.67945 0.3048)
			(stroke
				(width 0.1)
				(type default)
			)
			(layer "F.Fab")
		)
		(fp_line
			(start 0.120396 0.2794)
			(end -0.12065 0.2794)
			(stroke
				(width 0.1)
				(type default)
			)
			(layer "F.Fab")
		)
		(fp_line
			(start 0.120396 0.3048)
			(end 0.120396 0.2794)
			(stroke
				(width 0.1)
				(type default)
			)
			(layer "F.Fab")
		)
		(fp_line
			(start 0.12065 -0.3048)
			(end 0.67945 -0.3048)
			(stroke
				(width 0.1)
				(type default)
			)
			(layer "F.Fab")
		)
		(fp_line
			(start 0.12065 -0.2794)
			(end 0.12065 -0.3048)
			(stroke
				(width 0.1)
				(type default)
			)
			(layer "F.Fab")
		)
		(fp_line
			(start 0.67945 -0.3048)
			(end 0.67945 0.3048)
			(stroke
				(width 0.1)
				(type default)
			)
			(layer "F.Fab")
		)
		(fp_line
			(start 0.67945 0.3048)
			(end 0.120396 0.3048)
			(stroke
				(width 0.1)
				(type default)
			)
			(layer "F.Fab")
		)
		(pad "1" smd circle
			(at -0.40005 0)
			(size 0 0)
			(layers "F.Cu" "F.Mask" "F.Paste")
			(net "FM_SCM_PRSNT1_N")
		)
		(pad "2" smd circle
			(at 0.40005 0)
			(size 0 0)
			(layers "F.Cu" "F.Mask" "F.Paste")
			(net "FM_SCM_PRSNT1_R_N")
		)
	)
	(footprint ""
		(layer "F.Cu")
		(at 328.523092 -73.509378 90)
		(property "Reference" "R4303"
			(at 0 0 90)
			(layer "F.SilkS")
			(hide yes)
			(effects
				(font
					(size 1.27 1.27)
				)
			)
		)
		(property "Value" ""
			(at 0 0 90)
			(layer "F.Fab")
			(effects
				(font
					(size 1.27 1.27)
				)
			)
		)
		(duplicate_pad_numbers_are_jumpers no)
		(fp_line
			(start 0.7874 -0.4064)
			(end 0.7874 0.4064)
			(stroke
				(width 0.1524)
				(type default)
			)
			(layer "F.SilkS")
		)
		(fp_line
			(start -0.7874 -0.4064)
			(end 0.7874 -0.4064)
			(stroke
				(width 0.1524)
				(type default)
			)
			(layer "F.SilkS")
		)
		(fp_line
			(start 0.7874 0.4064)
			(end -0.7874 0.4064)
			(stroke
				(width 0.1524)
				(type default)
			)
			(layer "F.SilkS")
		)
		(fp_line
			(start -0.7874 0.4064)
			(end -0.7874 -0.4064)
			(stroke
				(width 0.1524)
				(type default)
			)
			(layer "F.SilkS")
		)
		(fp_line
			(start -0.12065 -0.305054)
			(end -0.12065 -0.2794)
			(stroke
				(width 0.1)
				(type default)
			)
			(layer "F.Fab")
		)
		(fp_line
			(start -0.67945 -0.305054)
			(end -0.12065 -0.305054)
			(stroke
				(width 0.1)
				(type default)
			)
			(layer "F.Fab")
		)
		(fp_line
			(start 0.67945 -0.3048)
			(end 0.67945 0.3048)
			(stroke
				(width 0.1)
				(type default)
			)
			(layer "F.Fab")
		)
		(fp_line
			(start 0.12065 -0.3048)
			(end 0.67945 -0.3048)
			(stroke
				(width 0.1)
				(type default)
			)
			(layer "F.Fab")
		)
		(fp_line
			(start 0.12065 -0.2794)
			(end 0.12065 -0.3048)
			(stroke
				(width 0.1)
				(type default)
			)
			(layer "F.Fab")
		)
		(fp_line
			(start -0.12065 -0.2794)
			(end 0.12065 -0.2794)
			(stroke
				(width 0.1)
				(type default)
			)
			(layer "F.Fab")
		)
		(fp_line
			(start 0.120396 0.2794)
			(end -0.12065 0.2794)
			(stroke
				(width 0.1)
				(type default)
			)
			(layer "F.Fab")
		)
		(fp_line
			(start -0.12065 0.2794)
			(end -0.12065 0.3048)
			(stroke
				(width 0.1)
				(type default)
			)
			(layer "F.Fab")
		)
		(fp_line
			(start 0.67945 0.3048)
			(end 0.120396 0.3048)
			(stroke
				(width 0.1)
				(type default)
			)
			(layer "F.Fab")
		)
		(fp_line
			(start 0.120396 0.3048)
			(end 0.120396 0.2794)
			(stroke
				(width 0.1)
				(type default)
			)
			(layer "F.Fab")
		)
		(fp_line
			(start -0.12065 0.3048)
			(end -0.67945 0.3048)
			(stroke
				(width 0.1)
				(type default)
			)
			(layer "F.Fab")
		)
		(fp_line
			(start -0.67945 0.3048)
			(end -0.67945 -0.305054)
			(stroke
				(width 0.1)
				(type default)
			)
			(layer "F.Fab")
		)
		(pad "1" smd circle
			(at -0.40005 0 90)
			(size 0 0)
			(layers "F.Cu" "F.Mask" "F.Paste")
			(net "CLK_100M_E1S_0_R_DP")
		)
		(pad "2" smd circle
			(at 0.40005 0 90)
			(size 0 0)
			(layers "F.Cu" "F.Mask" "F.Paste")
			(net "CLK_100M_E1S_0_DP")
		)
	)
)
